(kicad_pcb
	(version 20260206)
	(generator "pcbnew")
	(generator_version "10.0")
	(general
		(thickness 1.6)
		(legacy_teardrops no)
	)
	(paper "A4")
	(title_block
		(title "panther-plus-userver — 13130-1b_20150205.brd")
		(comment 1 "Honey Badger (Wiwynn) / footprint 406 of 1509 (DIMM2), pads 16-22 of 210")
	)
	(layers
		(0 "F.Cu" signal "TOP")
		(4 "In1.Cu" signal "L2")
		(6 "In2.Cu" signal "L3")
		(8 "In3.Cu" signal "L4")
		(10 "In4.Cu" signal "L5")
		(12 "In5.Cu" signal "L6")
		(14 "In6.Cu" signal "L7")
		(16 "In7.Cu" signal "L8")
		(18 "In8.Cu" signal "L9")
		(20 "In9.Cu" signal "L10")
		(22 "In10.Cu" signal "L11")
		(2 "B.Cu" signal "BOTTOM")
		(9 "F.Adhes" user "F.Adhesive")
		(11 "B.Adhes" user "B.Adhesive")
		(13 "F.Paste" user "Package Geometry/Pastemask Top")
		(15 "B.Paste" user "Package Geometry/Pastemask Bottom")
		(5 "F.SilkS" user "Ref Des/Silkscreen Top")
		(7 "B.SilkS" user "Ref Des/Silkscreen Bottom")
		(1 "F.Mask" user "Board Geometry/Soldermask Top")
		(3 "B.Mask" user "Board Geometry/Soldermask Bottom")
		(17 "Dwgs.User" user "User.Drawings")
		(19 "Cmts.User" user "User.Comments")
		(21 "Eco1.User" user "User.Eco1")
		(23 "Eco2.User" user "User.Eco2")
		(25 "Edge.Cuts" user "Board Geometry/Outline")
		(27 "Margin" user)
		(31 "F.CrtYd" user "Package Geometry/Place Bound Top")
		(29 "B.CrtYd" user "Package Geometry/Place Bound Bottom")
		(35 "F.Fab" user "Ref Des/Assembly Top")
		(33 "B.Fab" user "Ref Des/Assembly Bottom")
	)
	(footprint ""
		(layer "F.Cu")
		(at 158.500064 -66.699892 180)
		(property "Reference" "DIMM2"
			(at 0 0 180)
			(layer "F.SilkS")
			(hide yes)
			(effects
				(font
					(size 1.27 1.27)
				)
			)
		)
		(property "Value" "DDR3-204P-174-COLAY-1-GP"
			(at -40.682164 -17.468088 180)
			(unlocked yes)
			(layer "F.Fab")
			(hide yes)
			(effects
				(font
					(size 1.016 1.016)
					(thickness 0.1524)
				)
			)
		)
		(property "Device Type" "AS0A626-H8SN-7H-COLAY-1"
			(at -40.682164 -18.992088 180)
			(unlocked yes)
			(layer "F.Fab")
			(hide yes)
			(effects
				(font
					(size 1.016 1.016)
					(thickness 0.1524)
				)
			)
		)
		(duplicate_pad_numbers_are_jumpers no)
		(pad "14" smd custom
			(at -27.750008 -4.106672 180)
			(size 0.1143 0.1143)
			(layers "F.Cu" "F.Mask" "F.Paste")
			(net "GND")
			(options
				(clearance outline)
				(anchor circle)
			)
			(primitives
				(gr_poly
					(pts
						(xy 0 0.9017) (xy -0.03175 0.89916) (xy -0.0635 0.889) (xy -0.09144 0.87376) (xy -0.11684 0.85344)
						(xy -0.13716 0.82804) (xy -0.1524 0.8001) (xy -0.16256 0.76835) (xy -0.1651 0.7366) (xy -0.1651 0.44958)
						(xy -0.17272 0.44196) (xy -0.19812 0.4064) (xy -0.2032 0.39624) (xy -0.20701 0.38735) (xy -0.21209 0.37719)
						(xy -0.2159 0.36703) (xy -0.21844 0.35687) (xy -0.22225 0.34544) (xy -0.22352 0.33528) (xy -0.22606 0.32512)
						(xy -0.22733 0.31369) (xy -0.22733 0.30353) (xy -0.2286 0.2921) (xy -0.22733 0.28067) (xy -0.22733 0.27051)
						(xy -0.22606 0.25908) (xy -0.22352 0.24892) (xy -0.22225 0.23876) (xy -0.21844 0.22733) (xy -0.2159 0.21717)
						(xy -0.21209 0.20701) (xy -0.20701 0.19685) (xy -0.2032 0.18796) (xy -0.19812 0.1778) (xy -0.17272 0.14224)
						(xy -0.1651 0.13462) (xy -0.1651 -0.7366) (xy -0.16256 -0.76835) (xy -0.1524 -0.8001) (xy -0.13716 -0.82804)
						(xy -0.11684 -0.85344) (xy -0.09144 -0.87376) (xy -0.0635 -0.889) (xy -0.03175 -0.89916) (xy 0 -0.9017)
						(xy 0.03175 -0.89916) (xy 0.0635 -0.889) (xy 0.09144 -0.87376) (xy 0.11684 -0.85344) (xy 0.13716 -0.82804)
						(xy 0.1524 -0.8001) (xy 0.16256 -0.76835) (xy 0.1651 -0.7366) (xy 0.1651 0.13462) (xy 0.17272 0.14224)
						(xy 0.19812 0.1778) (xy 0.2032 0.18796) (xy 0.20701 0.19685) (xy 0.21209 0.20701) (xy 0.2159 0.21717)
						(xy 0.21844 0.22733) (xy 0.22225 0.23876) (xy 0.22352 0.24892) (xy 0.22606 0.25908) (xy 0.22733 0.27051)
						(xy 0.22733 0.28067) (xy 0.2286 0.2921) (xy 0.22733 0.30353) (xy 0.22733 0.31369) (xy 0.22606 0.32512)
						(xy 0.22352 0.33528) (xy 0.22225 0.34544) (xy 0.21844 0.35687) (xy 0.2159 0.36703) (xy 0.21209 0.37719)
						(xy 0.20701 0.38735) (xy 0.2032 0.39624) (xy 0.19812 0.4064) (xy 0.17272 0.44196) (xy 0.1651 0.44958)
						(xy 0.1651 0.7366) (xy 0.16256 0.76835) (xy 0.1524 0.8001) (xy 0.13716 0.82804) (xy 0.11684 0.85344)
						(xy 0.09144 0.87376) (xy 0.0635 0.889) (xy 0.03175 0.89916)
					)
					(width 0)
					(fill yes)
				)
			)
		)
		(pad "15" smd custom
			(at -27.450034 4.106672 180)
			(size 0.1143 0.1143)
			(layers "F.Cu" "F.Mask" "F.Paste")
			(net "M_A_DQ7")
			(options
				(clearance outline)
				(anchor circle)
			)
			(primitives
				(gr_poly
					(pts
						(xy 0 0.9017) (xy -0.03175 0.89916) (xy -0.0635 0.889) (xy -0.09144 0.87376) (xy -0.11684 0.85344)
						(xy -0.13716 0.82804) (xy -0.1524 0.8001) (xy -0.16256 0.76835) (xy -0.1651 0.7366) (xy -0.1651 0.11938)
						(xy -0.17272 0.11176) (xy -0.19812 0.0762) (xy -0.2032 0.06604) (xy -0.20701 0.05715) (xy -0.21209 0.04699)
						(xy -0.2159 0.03683) (xy -0.21844 0.02667) (xy -0.22225 0.01524) (xy -0.22352 0.00508) (xy -0.22606 -0.00508)
						(xy -0.22733 -0.01651) (xy -0.22733 -0.02667) (xy -0.2286 -0.0381) (xy -0.22733 -0.04953) (xy -0.22733 -0.05969)
						(xy -0.22606 -0.07112) (xy -0.22352 -0.08128) (xy -0.22225 -0.09144) (xy -0.21844 -0.10287) (xy -0.2159 -0.11303)
						(xy -0.21209 -0.12319) (xy -0.20701 -0.13335) (xy -0.2032 -0.14224) (xy -0.19812 -0.1524) (xy -0.17272 -0.18796)
						(xy -0.1651 -0.19558) (xy -0.1651 -0.7366) (xy -0.16256 -0.76835) (xy -0.1524 -0.8001) (xy -0.13716 -0.82804)
						(xy -0.11684 -0.85344) (xy -0.09144 -0.87376) (xy -0.0635 -0.889) (xy -0.03175 -0.89916) (xy 0 -0.9017)
						(xy 0.03175 -0.89916) (xy 0.0635 -0.889) (xy 0.09144 -0.87376) (xy 0.11684 -0.85344) (xy 0.13716 -0.82804)
						(xy 0.1524 -0.8001) (xy 0.16256 -0.76835) (xy 0.1651 -0.7366) (xy 0.1651 -0.19685) (xy 0.17272 -0.18923)
						(xy 0.17907 -0.18034) (xy 0.18669 -0.17145) (xy 0.19177 -0.16256) (xy 0.19812 -0.15367) (xy 0.20828 -0.13335)
						(xy 0.21971 -0.10287) (xy 0.22225 -0.09271) (xy 0.22479 -0.08128) (xy 0.22606 -0.07112) (xy 0.2286 -0.05969)
						(xy 0.2286 -0.01651) (xy 0.22606 -0.00508) (xy 0.22479 0.00508) (xy 0.22225 0.01651) (xy 0.21971 0.02667)
						(xy 0.20828 0.05715) (xy 0.19812 0.07747) (xy 0.19177 0.08636) (xy 0.18669 0.09525) (xy 0.17907 0.10414)
						(xy 0.17272 0.11303) (xy 0.1651 0.12065) (xy 0.1651 0.7366) (xy 0.16256 0.76835) (xy 0.1524 0.8001)
						(xy 0.13716 0.82804) (xy 0.11684 0.85344) (xy 0.09144 0.87376) (xy 0.0635 0.889) (xy 0.03175 0.89916)
					)
					(width 0)
					(fill yes)
				)
			)
		)
		(pad "16" smd custom
			(at -27.15006 -4.106672 180)
			(size 0.1143 0.1143)
			(layers "F.Cu" "F.Mask" "F.Paste")
			(net "M_A_DQ2")
			(options
				(clearance outline)
				(anchor circle)
			)
			(primitives
				(gr_poly
					(pts
						(xy 0 0.9017) (xy -0.03175 0.89916) (xy -0.0635 0.889) (xy -0.09144 0.87376) (xy -0.11684 0.85344)
						(xy -0.13716 0.82804) (xy -0.1524 0.8001) (xy -0.16256 0.76835) (xy -0.1651 0.7366) (xy -0.1651 0.19685)
						(xy -0.17272 0.18923) (xy -0.17907 0.18034) (xy -0.18669 0.17145) (xy -0.19177 0.16256) (xy -0.19812 0.15367)
						(xy -0.20828 0.13335) (xy -0.21971 0.10287) (xy -0.22225 0.09271) (xy -0.22479 0.08128) (xy -0.22606 0.07112)
						(xy -0.2286 0.05969) (xy -0.2286 0.01651) (xy -0.22606 0.00508) (xy -0.22479 -0.00508) (xy -0.22225 -0.01651)
						(xy -0.21971 -0.02667) (xy -0.20828 -0.05715) (xy -0.19812 -0.07747) (xy -0.19177 -0.08636) (xy -0.18669 -0.09525)
						(xy -0.17907 -0.10414) (xy -0.17272 -0.11303) (xy -0.1651 -0.12065) (xy -0.1651 -0.7366) (xy -0.16256 -0.76835)
						(xy -0.1524 -0.8001) (xy -0.13716 -0.82804) (xy -0.11684 -0.85344) (xy -0.09144 -0.87376) (xy -0.0635 -0.889)
						(xy -0.03175 -0.89916) (xy 0 -0.9017) (xy 0.03175 -0.89916) (xy 0.0635 -0.889) (xy 0.09144 -0.87376)
						(xy 0.11684 -0.85344) (xy 0.13716 -0.82804) (xy 0.1524 -0.8001) (xy 0.16256 -0.76835) (xy 0.1651 -0.7366)
						(xy 0.1651 -0.11938) (xy 0.17272 -0.11176) (xy 0.19812 -0.0762) (xy 0.2032 -0.06604) (xy 0.20701 -0.05715)
						(xy 0.21209 -0.04699) (xy 0.2159 -0.03683) (xy 0.21844 -0.02667) (xy 0.22225 -0.01524) (xy 0.22352 -0.00508)
						(xy 0.22606 0.00508) (xy 0.22733 0.01651) (xy 0.22733 0.02667) (xy 0.2286 0.0381) (xy 0.22733 0.04953)
						(xy 0.22733 0.05969) (xy 0.22606 0.07112) (xy 0.22352 0.08128) (xy 0.22225 0.09144) (xy 0.21844 0.10287)
						(xy 0.2159 0.11303) (xy 0.21209 0.12319) (xy 0.20701 0.13335) (xy 0.2032 0.14224) (xy 0.19812 0.1524)
						(xy 0.17272 0.18796) (xy 0.1651 0.19558) (xy 0.1651 0.7366) (xy 0.16256 0.76835) (xy 0.1524 0.8001)
						(xy 0.13716 0.82804) (xy 0.11684 0.85344) (xy 0.09144 0.87376) (xy 0.0635 0.889) (xy 0.03175 0.89916)
					)
					(width 0)
					(fill yes)
				)
			)
		)
		(pad "17" smd custom
			(at -26.850086 4.106672 180)
			(size 0.1143 0.1143)
			(layers "F.Cu" "F.Mask" "F.Paste")
			(net "GND")
			(options
				(clearance outline)
				(anchor circle)
			)
			(primitives
				(gr_poly
					(pts
						(xy 0 0.9017) (xy -0.03175 0.89916) (xy -0.0635 0.889) (xy -0.09144 0.87376) (xy -0.11684 0.85344)
						(xy -0.13716 0.82804) (xy -0.1524 0.8001) (xy -0.16256 0.76835) (xy -0.1651 0.7366) (xy -0.1651 -0.13462)
						(xy -0.17272 -0.14224) (xy -0.19812 -0.1778) (xy -0.2032 -0.18796) (xy -0.20701 -0.19685) (xy -0.21209 -0.20701)
						(xy -0.2159 -0.21717) (xy -0.21844 -0.22733) (xy -0.22225 -0.23876) (xy -0.22352 -0.24892) (xy -0.22606 -0.25908)
						(xy -0.22733 -0.27051) (xy -0.22733 -0.28067) (xy -0.2286 -0.2921) (xy -0.22733 -0.30353) (xy -0.22733 -0.31369)
						(xy -0.22606 -0.32512) (xy -0.22352 -0.33528) (xy -0.22225 -0.34544) (xy -0.21844 -0.35687) (xy -0.2159 -0.36703)
						(xy -0.21209 -0.37719) (xy -0.20701 -0.38735) (xy -0.2032 -0.39624) (xy -0.19812 -0.4064) (xy -0.17272 -0.44196)
						(xy -0.1651 -0.44958) (xy -0.1651 -0.7366) (xy -0.16256 -0.76835) (xy -0.1524 -0.8001) (xy -0.13716 -0.82804)
						(xy -0.11684 -0.85344) (xy -0.09144 -0.87376) (xy -0.0635 -0.889) (xy -0.03175 -0.89916) (xy 0 -0.9017)
						(xy 0.03175 -0.89916) (xy 0.0635 -0.889) (xy 0.09144 -0.87376) (xy 0.11684 -0.85344) (xy 0.13716 -0.82804)
						(xy 0.1524 -0.8001) (xy 0.16256 -0.76835) (xy 0.1651 -0.7366) (xy 0.1651 -0.44958) (xy 0.17272 -0.44196)
						(xy 0.19812 -0.4064) (xy 0.2032 -0.39624) (xy 0.20701 -0.38735) (xy 0.21209 -0.37719) (xy 0.2159 -0.36703)
						(xy 0.21844 -0.35687) (xy 0.22225 -0.34544) (xy 0.22352 -0.33528) (xy 0.22606 -0.32512) (xy 0.22733 -0.31369)
						(xy 0.22733 -0.30353) (xy 0.2286 -0.2921) (xy 0.22733 -0.28067) (xy 0.22733 -0.27051) (xy 0.22606 -0.25908)
						(xy 0.22352 -0.24892) (xy 0.22225 -0.23876) (xy 0.21844 -0.22733) (xy 0.2159 -0.21717) (xy 0.21209 -0.20701)
						(xy 0.20701 -0.19685) (xy 0.2032 -0.18796) (xy 0.19812 -0.1778) (xy 0.17272 -0.14224) (xy 0.1651 -0.13462)
						(xy 0.1651 0.7366) (xy 0.16256 0.76835) (xy 0.1524 0.8001) (xy 0.13716 0.82804) (xy 0.11684 0.85344)
						(xy 0.09144 0.87376) (xy 0.0635 0.889) (xy 0.03175 0.89916)
					)
					(width 0)
					(fill yes)
				)
			)
		)
		(pad "18" smd custom
			(at -26.550112 -4.106672 180)
			(size 0.1143 0.1143)
			(layers "F.Cu" "F.Mask" "F.Paste")
			(net "M_A_DQ3")
			(options
				(clearance outline)
				(anchor circle)
			)
			(primitives
				(gr_poly
					(pts
						(xy 0 0.9017) (xy -0.03175 0.89916) (xy -0.0635 0.889) (xy -0.09144 0.87376) (xy -0.11684 0.85344)
						(xy -0.13716 0.82804) (xy -0.1524 0.8001) (xy -0.16256 0.76835) (xy -0.1651 0.7366) (xy -0.1651 0.44958)
						(xy -0.17272 0.44196) (xy -0.19812 0.4064) (xy -0.2032 0.39624) (xy -0.20701 0.38735) (xy -0.21209 0.37719)
						(xy -0.2159 0.36703) (xy -0.21844 0.35687) (xy -0.22225 0.34544) (xy -0.22352 0.33528) (xy -0.22606 0.32512)
						(xy -0.22733 0.31369) (xy -0.22733 0.30353) (xy -0.2286 0.2921) (xy -0.22733 0.28067) (xy -0.22733 0.27051)
						(xy -0.22606 0.25908) (xy -0.22352 0.24892) (xy -0.22225 0.23876) (xy -0.21844 0.22733) (xy -0.2159 0.21717)
						(xy -0.21209 0.20701) (xy -0.20701 0.19685) (xy -0.2032 0.18796) (xy -0.19812 0.1778) (xy -0.17272 0.14224)
						(xy -0.1651 0.13462) (xy -0.1651 -0.7366) (xy -0.16256 -0.76835) (xy -0.1524 -0.8001) (xy -0.13716 -0.82804)
						(xy -0.11684 -0.85344) (xy -0.09144 -0.87376) (xy -0.0635 -0.889) (xy -0.03175 -0.89916) (xy 0 -0.9017)
						(xy 0.03175 -0.89916) (xy 0.0635 -0.889) (xy 0.09144 -0.87376) (xy 0.11684 -0.85344) (xy 0.13716 -0.82804)
						(xy 0.1524 -0.8001) (xy 0.16256 -0.76835) (xy 0.1651 -0.7366) (xy 0.1651 0.13462) (xy 0.17272 0.14224)
						(xy 0.19812 0.1778) (xy 0.2032 0.18796) (xy 0.20701 0.19685) (xy 0.21209 0.20701) (xy 0.2159 0.21717)
						(xy 0.21844 0.22733) (xy 0.22225 0.23876) (xy 0.22352 0.24892) (xy 0.22606 0.25908) (xy 0.22733 0.27051)
						(xy 0.22733 0.28067) (xy 0.2286 0.2921) (xy 0.22733 0.30353) (xy 0.22733 0.31369) (xy 0.22606 0.32512)
						(xy 0.22352 0.33528) (xy 0.22225 0.34544) (xy 0.21844 0.35687) (xy 0.2159 0.36703) (xy 0.21209 0.37719)
						(xy 0.20701 0.38735) (xy 0.2032 0.39624) (xy 0.19812 0.4064) (xy 0.17272 0.44196) (xy 0.1651 0.44958)
						(xy 0.1651 0.7366) (xy 0.16256 0.76835) (xy 0.1524 0.8001) (xy 0.13716 0.82804) (xy 0.11684 0.85344)
						(xy 0.09144 0.87376) (xy 0.0635 0.889) (xy 0.03175 0.89916)
					)
					(width 0)
					(fill yes)
				)
			)
		)
		(pad "19" smd custom
			(at -26.249884 4.106672 180)
			(size 0.1143 0.1143)
			(layers "F.Cu" "F.Mask" "F.Paste")
			(net "M_A_DQ12")
			(options
				(clearance outline)
				(anchor circle)
			)
			(primitives
				(gr_poly
					(pts
						(xy 0 0.9017) (xy -0.03175 0.89916) (xy -0.0635 0.889) (xy -0.09144 0.87376) (xy -0.11684 0.85344)
						(xy -0.13716 0.82804) (xy -0.1524 0.8001) (xy -0.16256 0.76835) (xy -0.1651 0.7366) (xy -0.1651 0.11938)
						(xy -0.17272 0.11176) (xy -0.19812 0.0762) (xy -0.2032 0.06604) (xy -0.20701 0.05715) (xy -0.21209 0.04699)
						(xy -0.2159 0.03683) (xy -0.21844 0.02667) (xy -0.22225 0.01524) (xy -0.22352 0.00508) (xy -0.22606 -0.00508)
						(xy -0.22733 -0.01651) (xy -0.22733 -0.02667) (xy -0.2286 -0.0381) (xy -0.22733 -0.04953) (xy -0.22733 -0.05969)
						(xy -0.22606 -0.07112) (xy -0.22352 -0.08128) (xy -0.22225 -0.09144) (xy -0.21844 -0.10287) (xy -0.2159 -0.11303)
						(xy -0.21209 -0.12319) (xy -0.20701 -0.13335) (xy -0.2032 -0.14224) (xy -0.19812 -0.1524) (xy -0.17272 -0.18796)
						(xy -0.1651 -0.19558) (xy -0.1651 -0.7366) (xy -0.16256 -0.76835) (xy -0.1524 -0.8001) (xy -0.13716 -0.82804)
						(xy -0.11684 -0.85344) (xy -0.09144 -0.87376) (xy -0.0635 -0.889) (xy -0.03175 -0.89916) (xy 0 -0.9017)
						(xy 0.03175 -0.89916) (xy 0.0635 -0.889) (xy 0.09144 -0.87376) (xy 0.11684 -0.85344) (xy 0.13716 -0.82804)
						(xy 0.1524 -0.8001) (xy 0.16256 -0.76835) (xy 0.1651 -0.7366) (xy 0.1651 -0.19685) (xy 0.17272 -0.18923)
						(xy 0.17907 -0.18034) (xy 0.18669 -0.17145) (xy 0.19177 -0.16256) (xy 0.19812 -0.15367) (xy 0.20828 -0.13335)
						(xy 0.21971 -0.10287) (xy 0.22225 -0.09271) (xy 0.22479 -0.08128) (xy 0.22606 -0.07112) (xy 0.2286 -0.05969)
						(xy 0.2286 -0.01651) (xy 0.22606 -0.00508) (xy 0.22479 0.00508) (xy 0.22225 0.01651) (xy 0.21971 0.02667)
						(xy 0.20828 0.05715) (xy 0.19812 0.07747) (xy 0.19177 0.08636) (xy 0.18669 0.09525) (xy 0.17907 0.10414)
						(xy 0.17272 0.11303) (xy 0.1651 0.12065) (xy 0.1651 0.7366) (xy 0.16256 0.76835) (xy 0.1524 0.8001)
						(xy 0.13716 0.82804) (xy 0.11684 0.85344) (xy 0.09144 0.87376) (xy 0.0635 0.889) (xy 0.03175 0.89916)
					)
					(width 0)
					(fill yes)
				)
			)
		)
		(pad "20" smd custom
			(at -25.94991 -4.106672 180)
			(size 0.1143 0.1143)
			(layers "F.Cu" "F.Mask" "F.Paste")
			(net "GND")
			(options
				(clearance outline)
				(anchor circle)
			)
			(primitives
				(gr_poly
					(pts
						(xy 0 0.9017) (xy -0.03175 0.89916) (xy -0.0635 0.889) (xy -0.09144 0.87376) (xy -0.11684 0.85344)
						(xy -0.13716 0.82804) (xy -0.1524 0.8001) (xy -0.16256 0.76835) (xy -0.1651 0.7366) (xy -0.1651 0.19685)
						(xy -0.17272 0.18923) (xy -0.17907 0.18034) (xy -0.18669 0.17145) (xy -0.19177 0.16256) (xy -0.19812 0.15367)
						(xy -0.20828 0.13335) (xy -0.21971 0.10287) (xy -0.22225 0.09271) (xy -0.22479 0.08128) (xy -0.22606 0.07112)
						(xy -0.2286 0.05969) (xy -0.2286 0.01651) (xy -0.22606 0.00508) (xy -0.22479 -0.00508) (xy -0.22225 -0.01651)
						(xy -0.21971 -0.02667) (xy -0.20828 -0.05715) (xy -0.19812 -0.07747) (xy -0.19177 -0.08636) (xy -0.18669 -0.09525)
						(xy -0.17907 -0.10414) (xy -0.17272 -0.11303) (xy -0.1651 -0.12065) (xy -0.1651 -0.7366) (xy -0.16256 -0.76835)
						(xy -0.1524 -0.8001) (xy -0.13716 -0.82804) (xy -0.11684 -0.85344) (xy -0.09144 -0.87376) (xy -0.0635 -0.889)
						(xy -0.03175 -0.89916) (xy 0 -0.9017) (xy 0.03175 -0.89916) (xy 0.0635 -0.889) (xy 0.09144 -0.87376)
						(xy 0.11684 -0.85344) (xy 0.13716 -0.82804) (xy 0.1524 -0.8001) (xy 0.16256 -0.76835) (xy 0.1651 -0.7366)
						(xy 0.1651 -0.11938) (xy 0.17272 -0.11176) (xy 0.19812 -0.0762) (xy 0.2032 -0.06604) (xy 0.20701 -0.05715)
						(xy 0.21209 -0.04699) (xy 0.2159 -0.03683) (xy 0.21844 -0.02667) (xy 0.22225 -0.01524) (xy 0.22352 -0.00508)
						(xy 0.22606 0.00508) (xy 0.22733 0.01651) (xy 0.22733 0.02667) (xy 0.2286 0.0381) (xy 0.22733 0.04953)
						(xy 0.22733 0.05969) (xy 0.22606 0.07112) (xy 0.22352 0.08128) (xy 0.22225 0.09144) (xy 0.21844 0.10287)
						(xy 0.2159 0.11303) (xy 0.21209 0.12319) (xy 0.20701 0.13335) (xy 0.2032 0.14224) (xy 0.19812 0.1524)
						(xy 0.17272 0.18796) (xy 0.1651 0.19558) (xy 0.1651 0.7366) (xy 0.16256 0.76835) (xy 0.1524 0.8001)
						(xy 0.13716 0.82804) (xy 0.11684 0.85344) (xy 0.09144 0.87376) (xy 0.0635 0.889) (xy 0.03175 0.89916)
					)
					(width 0)
					(fill yes)
				)
			)
		)
	)
)
